(kicad_pcb
	(version 20260206)
	(generator "pcbnew")
	(generator_version "10.0")
	(general
		(thickness 1.6)
		(legacy_teardrops no)
	)
	(paper "A4")
	(title_block
		(title "04192023_DAF0TMB3IC0_F0TG_MB_C_brd_V02_OCP.brd")
		(comment 1 "Grand Teton / footprints 8119-8126 of 8354")
	)
	(layers
		(0 "F.Cu" signal "TOP")
		(4 "In1.Cu" signal "GND")
		(6 "In2.Cu" signal "IN1")
		(8 "In3.Cu" signal "GND1")
		(10 "In4.Cu" signal "IN2")
		(12 "In5.Cu" signal "GND2")
		(14 "In6.Cu" signal "IN3")
		(16 "In7.Cu" signal "GND3")
		(18 "In8.Cu" signal "VCC")
		(20 "In9.Cu" signal "VCC1")
		(22 "In10.Cu" signal "GND4")
		(24 "In11.Cu" signal "IN4")
		(26 "In12.Cu" signal "GND5")
		(28 "In13.Cu" signal "IN5")
		(30 "In14.Cu" signal "GND6")
		(32 "In15.Cu" signal "IN6")
		(34 "In16.Cu" signal "GND7")
		(2 "B.Cu" signal "BOTTOM")
		(9 "F.Adhes" user "F.Adhesive")
		(11 "B.Adhes" user "B.Adhesive")
		(13 "F.Paste" user "Package Geometry/Pastemask Top")
		(15 "B.Paste" user "Package Geometry/Pastemask Bottom")
		(5 "F.SilkS" user "Ref Des/Silkscreen Top")
		(7 "B.SilkS" user "Ref Des/Silkscreen Bottom")
		(1 "F.Mask" user "Board Geometry/Soldermask Top")
		(3 "B.Mask" user "Board Geometry/Soldermask Bottom")
		(17 "Dwgs.User" user "User.Drawings")
		(19 "Cmts.User" user "User.Comments")
		(21 "Eco1.User" user "User.Eco1")
		(23 "Eco2.User" user "User.Eco2")
		(25 "Edge.Cuts" user "Board Geometry/Outline")
		(27 "Margin" user)
		(31 "F.CrtYd" user "Package Geometry/Place Bound Top")
		(29 "B.CrtYd" user "Package Geometry/Place Bound Bottom")
		(35 "F.Fab" user "Ref Des/Assembly Top")
		(33 "B.Fab" user "Ref Des/Assembly Bottom")
	)
	(footprint ""
		(layer "B.Cu")
		(at 175.316388 -193.996564)
		(property "Reference" "C164"
			(at 0 0 0)
			(layer "B.SilkS")
			(hide yes)
			(effects
				(font
					(size 1.27 1.27)
				)
				(justify mirror)
			)
		)
		(property "Value" ""
			(at 0 0 0)
			(layer "B.Fab")
			(effects
				(font
					(size 1.27 1.27)
				)
				(justify mirror)
			)
		)
		(duplicate_pad_numbers_are_jumpers no)
		(fp_line
			(start -0.7874 -0.4064)
			(end -0.7874 0.4064)
			(stroke
				(width 0.1524)
				(type default)
			)
			(layer "B.SilkS")
		)
		(fp_line
			(start -0.7874 0.4064)
			(end 0.7874 0.4064)
			(stroke
				(width 0.1524)
				(type default)
			)
			(layer "B.SilkS")
		)
		(fp_line
			(start 0.7874 -0.4064)
			(end -0.7874 -0.4064)
			(stroke
				(width 0.1524)
				(type default)
			)
			(layer "B.SilkS")
		)
		(fp_line
			(start 0.7874 0.4064)
			(end 0.7874 -0.4064)
			(stroke
				(width 0.1524)
				(type default)
			)
			(layer "B.SilkS")
		)
		(fp_line
			(start -0.67945 -0.3048)
			(end -0.67945 0.3048)
			(stroke
				(width 0.1)
				(type default)
			)
			(layer "B.Fab")
		)
		(fp_line
			(start -0.67945 0.3048)
			(end -0.120396 0.3048)
			(stroke
				(width 0.1)
				(type default)
			)
			(layer "B.Fab")
		)
		(fp_line
			(start -0.12065 -0.3048)
			(end -0.67945 -0.3048)
			(stroke
				(width 0.1)
				(type default)
			)
			(layer "B.Fab")
		)
		(fp_line
			(start -0.12065 -0.2794)
			(end -0.12065 -0.3048)
			(stroke
				(width 0.1)
				(type default)
			)
			(layer "B.Fab")
		)
		(fp_line
			(start -0.120396 0.2794)
			(end 0.12065 0.2794)
			(stroke
				(width 0.1)
				(type default)
			)
			(layer "B.Fab")
		)
		(fp_line
			(start -0.120396 0.3048)
			(end -0.120396 0.2794)
			(stroke
				(width 0.1)
				(type default)
			)
			(layer "B.Fab")
		)
		(fp_line
			(start 0.12065 -0.305054)
			(end 0.12065 -0.2794)
			(stroke
				(width 0.1)
				(type default)
			)
			(layer "B.Fab")
		)
		(fp_line
			(start 0.12065 -0.2794)
			(end -0.12065 -0.2794)
			(stroke
				(width 0.1)
				(type default)
			)
			(layer "B.Fab")
		)
		(fp_line
			(start 0.12065 0.2794)
			(end 0.12065 0.3048)
			(stroke
				(width 0.1)
				(type default)
			)
			(layer "B.Fab")
		)
		(fp_line
			(start 0.12065 0.3048)
			(end 0.67945 0.3048)
			(stroke
				(width 0.1)
				(type default)
			)
			(layer "B.Fab")
		)
		(fp_line
			(start 0.67945 -0.305054)
			(end 0.12065 -0.305054)
			(stroke
				(width 0.1)
				(type default)
			)
			(layer "B.Fab")
		)
		(fp_line
			(start 0.67945 0.3048)
			(end 0.67945 -0.305054)
			(stroke
				(width 0.1)
				(type default)
			)
			(layer "B.Fab")
		)
		(pad "1" smd circle
			(at 0.40005 0 180)
			(size 0 0)
			(layers "B.Cu" "B.Mask" "B.Paste")
			(net "P3V3_AUX")
		)
		(pad "2" smd circle
			(at -0.40005 0 180)
			(size 0 0)
			(layers "B.Cu" "B.Mask" "B.Paste")
			(net "GND")
		)
	)
	(footprint ""
		(layer "B.Cu")
		(at 98.984054 -326.825102 -90)
		(property "Reference" "PC430_5"
			(at 0 0 90)
			(layer "B.SilkS")
			(hide yes)
			(effects
				(font
					(size 1.27 1.27)
				)
				(justify mirror)
			)
		)
		(property "Value" ""
			(at 0 0 90)
			(layer "B.Fab")
			(effects
				(font
					(size 1.27 1.27)
				)
				(justify mirror)
			)
		)
		(duplicate_pad_numbers_are_jumpers no)
		(fp_line
			(start -1.524 0.762)
			(end 1.524 0.762)
			(stroke
				(width 0.1524)
				(type default)
			)
			(layer "B.SilkS")
		)
		(fp_line
			(start 1.524 0.762)
			(end 1.524 -0.762)
			(stroke
				(width 0.1524)
				(type default)
			)
			(layer "B.SilkS")
		)
		(fp_line
			(start -1.524 -0.762)
			(end -1.524 0.762)
			(stroke
				(width 0.1524)
				(type default)
			)
			(layer "B.SilkS")
		)
		(fp_line
			(start 1.524 -0.762)
			(end -1.524 -0.762)
			(stroke
				(width 0.1524)
				(type default)
			)
			(layer "B.SilkS")
		)
		(fp_line
			(start -1.1049 0.724916)
			(end -1.1049 -0.724916)
			(stroke
				(width 0.1)
				(type default)
			)
			(layer "B.Fab")
		)
		(fp_line
			(start 1.1049 0.724916)
			(end -1.1049 0.724916)
			(stroke
				(width 0.1)
				(type default)
			)
			(layer "B.Fab")
		)
		(fp_line
			(start -1.1049 -0.724916)
			(end 1.1049 -0.724916)
			(stroke
				(width 0.1)
				(type default)
			)
			(layer "B.Fab")
		)
		(fp_line
			(start 1.1049 -0.724916)
			(end 1.1049 0.724916)
			(stroke
				(width 0.1)
				(type default)
			)
			(layer "B.Fab")
		)
		(pad "1" smd rect
			(at 0.889 0 270)
			(size 1.016 1.27)
			(layers "B.Cu" "B.Mask" "B.Paste")
			(net "PVDDCR_CPU1_P1")
		)
		(pad "2" smd rect
			(at -0.889 0 270)
			(size 1.016 1.27)
			(layers "B.Cu" "B.Mask" "B.Paste")
			(net "GND")
		)
	)
	(footprint ""
		(layer "B.Cu")
		(at 187.349384 -13.60043 -90)
		(property "Reference" "R6003"
			(at 0 0 90)
			(layer "B.SilkS")
			(hide yes)
			(effects
				(font
					(size 1.27 1.27)
				)
				(justify mirror)
			)
		)
		(property "Value" ""
			(at 0 0 90)
			(layer "B.Fab")
			(effects
				(font
					(size 1.27 1.27)
				)
				(justify mirror)
			)
		)
		(duplicate_pad_numbers_are_jumpers no)
		(fp_line
			(start -0.7874 0.4064)
			(end 0.7874 0.4064)
			(stroke
				(width 0.1524)
				(type default)
			)
			(layer "B.SilkS")
		)
		(fp_line
			(start 0.7874 0.4064)
			(end 0.7874 -0.4064)
			(stroke
				(width 0.1524)
				(type default)
			)
			(layer "B.SilkS")
		)
		(fp_line
			(start -0.7874 -0.4064)
			(end -0.7874 0.4064)
			(stroke
				(width 0.1524)
				(type default)
			)
			(layer "B.SilkS")
		)
		(fp_line
			(start 0.7874 -0.4064)
			(end -0.7874 -0.4064)
			(stroke
				(width 0.1524)
				(type default)
			)
			(layer "B.SilkS")
		)
		(fp_line
			(start -0.67945 0.3048)
			(end -0.120396 0.3048)
			(stroke
				(width 0.1)
				(type default)
			)
			(layer "B.Fab")
		)
		(fp_line
			(start -0.120396 0.3048)
			(end -0.120396 0.2794)
			(stroke
				(width 0.1)
				(type default)
			)
			(layer "B.Fab")
		)
		(fp_line
			(start 0.12065 0.3048)
			(end 0.67945 0.3048)
			(stroke
				(width 0.1)
				(type default)
			)
			(layer "B.Fab")
		)
		(fp_line
			(start 0.67945 0.3048)
			(end 0.67945 -0.305054)
			(stroke
				(width 0.1)
				(type default)
			)
			(layer "B.Fab")
		)
		(fp_line
			(start -0.120396 0.2794)
			(end 0.12065 0.2794)
			(stroke
				(width 0.1)
				(type default)
			)
			(layer "B.Fab")
		)
		(fp_line
			(start 0.12065 0.2794)
			(end 0.12065 0.3048)
			(stroke
				(width 0.1)
				(type default)
			)
			(layer "B.Fab")
		)
		(fp_line
			(start -0.12065 -0.2794)
			(end -0.12065 -0.3048)
			(stroke
				(width 0.1)
				(type default)
			)
			(layer "B.Fab")
		)
		(fp_line
			(start 0.12065 -0.2794)
			(end -0.12065 -0.2794)
			(stroke
				(width 0.1)
				(type default)
			)
			(layer "B.Fab")
		)
		(fp_line
			(start -0.67945 -0.3048)
			(end -0.67945 0.3048)
			(stroke
				(width 0.1)
				(type default)
			)
			(layer "B.Fab")
		)
		(fp_line
			(start -0.12065 -0.3048)
			(end -0.67945 -0.3048)
			(stroke
				(width 0.1)
				(type default)
			)
			(layer "B.Fab")
		)
		(fp_line
			(start 0.12065 -0.305054)
			(end 0.12065 -0.2794)
			(stroke
				(width 0.1)
				(type default)
			)
			(layer "B.Fab")
		)
		(fp_line
			(start 0.67945 -0.305054)
			(end 0.12065 -0.305054)
			(stroke
				(width 0.1)
				(type default)
			)
			(layer "B.Fab")
		)
		(pad "1" smd circle
			(at 0.40005 0 90)
			(size 0 0)
			(layers "B.Cu" "B.Mask" "B.Paste")
			(net "I3C_SCM_1_SDA")
		)
		(pad "2" smd circle
			(at -0.40005 0 90)
			(size 0 0)
			(layers "B.Cu" "B.Mask" "B.Paste")
			(net "I3C_SCM_1_R_SDA")
		)
	)
	(footprint ""
		(layer "B.Cu")
		(at 91.493594 -303.255172 180)
		(property "Reference" "R519"
			(at 0 0 0)
			(layer "B.SilkS")
			(hide yes)
			(effects
				(font
					(size 1.27 1.27)
				)
				(justify mirror)
			)
		)
		(property "Value" ""
			(at 0 0 0)
			(layer "B.Fab")
			(effects
				(font
					(size 1.27 1.27)
				)
				(justify mirror)
			)
		)
		(duplicate_pad_numbers_are_jumpers no)
		(fp_line
			(start 0.7874 0.4064)
			(end 0.7874 -0.4064)
			(stroke
				(width 0.1524)
				(type default)
			)
			(layer "B.SilkS")
		)
		(fp_line
			(start 0.7874 -0.4064)
			(end -0.7874 -0.4064)
			(stroke
				(width 0.1524)
				(type default)
			)
			(layer "B.SilkS")
		)
		(fp_line
			(start -0.7874 0.4064)
			(end 0.7874 0.4064)
			(stroke
				(width 0.1524)
				(type default)
			)
			(layer "B.SilkS")
		)
		(fp_line
			(start -0.7874 -0.4064)
			(end -0.7874 0.4064)
			(stroke
				(width 0.1524)
				(type default)
			)
			(layer "B.SilkS")
		)
		(fp_line
			(start 0.67945 0.3048)
			(end 0.67945 -0.305054)
			(stroke
				(width 0.1)
				(type default)
			)
			(layer "B.Fab")
		)
		(fp_line
			(start 0.67945 -0.305054)
			(end 0.12065 -0.305054)
			(stroke
				(width 0.1)
				(type default)
			)
			(layer "B.Fab")
		)
		(fp_line
			(start 0.12065 0.3048)
			(end 0.67945 0.3048)
			(stroke
				(width 0.1)
				(type default)
			)
			(layer "B.Fab")
		)
		(fp_line
			(start 0.12065 0.2794)
			(end 0.12065 0.3048)
			(stroke
				(width 0.1)
				(type default)
			)
			(layer "B.Fab")
		)
		(fp_line
			(start 0.12065 -0.2794)
			(end -0.12065 -0.2794)
			(stroke
				(width 0.1)
				(type default)
			)
			(layer "B.Fab")
		)
		(fp_line
			(start 0.12065 -0.305054)
			(end 0.12065 -0.2794)
			(stroke
				(width 0.1)
				(type default)
			)
			(layer "B.Fab")
		)
		(fp_line
			(start -0.120396 0.3048)
			(end -0.120396 0.2794)
			(stroke
				(width 0.1)
				(type default)
			)
			(layer "B.Fab")
		)
		(fp_line
			(start -0.120396 0.2794)
			(end 0.12065 0.2794)
			(stroke
				(width 0.1)
				(type default)
			)
			(layer "B.Fab")
		)
		(fp_line
			(start -0.12065 -0.2794)
			(end -0.12065 -0.3048)
			(stroke
				(width 0.1)
				(type default)
			)
			(layer "B.Fab")
		)
		(fp_line
			(start -0.12065 -0.3048)
			(end -0.67945 -0.3048)
			(stroke
				(width 0.1)
				(type default)
			)
			(layer "B.Fab")
		)
		(fp_line
			(start -0.67945 0.3048)
			(end -0.120396 0.3048)
			(stroke
				(width 0.1)
				(type default)
			)
			(layer "B.Fab")
		)
		(fp_line
			(start -0.67945 -0.3048)
			(end -0.67945 0.3048)
			(stroke
				(width 0.1)
				(type default)
			)
			(layer "B.Fab")
		)
		(pad "1" smd circle
			(at 0.40005 0)
			(size 0 0)
			(layers "B.Cu" "B.Mask" "B.Paste")
			(net "CPU1_SA0")
		)
		(pad "2" smd circle
			(at -0.40005 0)
			(size 0 0)
			(layers "B.Cu" "B.Mask" "B.Paste")
			(net "GND")
		)
	)
	(footprint ""
		(layer "B.Cu")
		(at 406.606248 -395.148562 90)
		(property "Reference" "C783"
			(at 0 0 90)
			(layer "B.SilkS")
			(hide yes)
			(effects
				(font
					(size 1.27 1.27)
				)
				(justify mirror)
			)
		)
		(property "Value" ""
			(at 0 0 90)
			(layer "B.Fab")
			(effects
				(font
					(size 1.27 1.27)
				)
				(justify mirror)
			)
		)
		(duplicate_pad_numbers_are_jumpers no)
		(fp_line
			(start 0.299974 -0.150114)
			(end -0.299974 -0.150114)
			(stroke
				(width 0.1)
				(type default)
			)
			(layer "B.Fab")
		)
		(fp_line
			(start -0.299974 -0.150114)
			(end -0.299974 0.150114)
			(stroke
				(width 0.1)
				(type default)
			)
			(layer "B.Fab")
		)
		(fp_line
			(start 0.299974 0.150114)
			(end 0.299974 -0.150114)
			(stroke
				(width 0.1)
				(type default)
			)
			(layer "B.Fab")
		)
		(fp_line
			(start -0.299974 0.150114)
			(end 0.299974 0.150114)
			(stroke
				(width 0.1)
				(type default)
			)
			(layer "B.Fab")
		)
		(pad "1" smd rect
			(at 0.2667 0 270)
			(size 0.3048 0.381)
			(layers "B.Cu" "B.Mask" "B.Paste")
			(net "P0V9_CPU0_RT2_2A")
		)
		(pad "2" smd rect
			(at -0.2667 0 270)
			(size 0.3048 0.381)
			(layers "B.Cu" "B.Mask" "B.Paste")
			(net "GND")
		)
	)
	(footprint ""
		(layer "B.Cu")
		(at 304.419 -361.696 180)
		(property "Reference" "R8058"
			(at 0 0 0)
			(layer "B.SilkS")
			(hide yes)
			(effects
				(font
					(size 1.27 1.27)
				)
				(justify mirror)
			)
		)
		(property "Value" ""
			(at 0 0 0)
			(layer "B.Fab")
			(effects
				(font
					(size 1.27 1.27)
				)
				(justify mirror)
			)
		)
		(duplicate_pad_numbers_are_jumpers no)
		(fp_line
			(start 0.7874 0.4064)
			(end 0.7874 -0.4064)
			(stroke
				(width 0.1524)
				(type default)
			)
			(layer "B.SilkS")
		)
		(fp_line
			(start 0.7874 -0.4064)
			(end -0.7874 -0.4064)
			(stroke
				(width 0.1524)
				(type default)
			)
			(layer "B.SilkS")
		)
		(fp_line
			(start -0.7874 0.4064)
			(end 0.7874 0.4064)
			(stroke
				(width 0.1524)
				(type default)
			)
			(layer "B.SilkS")
		)
		(fp_line
			(start -0.7874 -0.4064)
			(end -0.7874 0.4064)
			(stroke
				(width 0.1524)
				(type default)
			)
			(layer "B.SilkS")
		)
		(fp_line
			(start 0.67945 0.3048)
			(end 0.67945 -0.305054)
			(stroke
				(width 0.1)
				(type default)
			)
			(layer "B.Fab")
		)
		(fp_line
			(start 0.67945 -0.305054)
			(end 0.12065 -0.305054)
			(stroke
				(width 0.1)
				(type default)
			)
			(layer "B.Fab")
		)
		(fp_line
			(start 0.12065 0.3048)
			(end 0.67945 0.3048)
			(stroke
				(width 0.1)
				(type default)
			)
			(layer "B.Fab")
		)
		(fp_line
			(start 0.12065 0.2794)
			(end 0.12065 0.3048)
			(stroke
				(width 0.1)
				(type default)
			)
			(layer "B.Fab")
		)
		(fp_line
			(start 0.12065 -0.2794)
			(end -0.12065 -0.2794)
			(stroke
				(width 0.1)
				(type default)
			)
			(layer "B.Fab")
		)
		(fp_line
			(start 0.12065 -0.305054)
			(end 0.12065 -0.2794)
			(stroke
				(width 0.1)
				(type default)
			)
			(layer "B.Fab")
		)
		(fp_line
			(start -0.120396 0.3048)
			(end -0.120396 0.2794)
			(stroke
				(width 0.1)
				(type default)
			)
			(layer "B.Fab")
		)
		(fp_line
			(start -0.120396 0.2794)
			(end 0.12065 0.2794)
			(stroke
				(width 0.1)
				(type default)
			)
			(layer "B.Fab")
		)
		(fp_line
			(start -0.12065 -0.2794)
			(end -0.12065 -0.3048)
			(stroke
				(width 0.1)
				(type default)
			)
			(layer "B.Fab")
		)
		(fp_line
			(start -0.12065 -0.3048)
			(end -0.67945 -0.3048)
			(stroke
				(width 0.1)
				(type default)
			)
			(layer "B.Fab")
		)
		(fp_line
			(start -0.67945 0.3048)
			(end -0.120396 0.3048)
			(stroke
				(width 0.1)
				(type default)
			)
			(layer "B.Fab")
		)
		(fp_line
			(start -0.67945 -0.3048)
			(end -0.67945 0.3048)
			(stroke
				(width 0.1)
				(type default)
			)
			(layer "B.Fab")
		)
		(pad "1" smd circle
			(at 0.40005 0)
			(size 0 0)
			(layers "B.Cu" "B.Mask" "B.Paste")
			(net "FM_PVDDCR_CPU1_P0_EN")
		)
		(pad "2" smd circle
			(at -0.40005 0)
			(size 0 0)
			(layers "B.Cu" "B.Mask" "B.Paste")
			(net "PVDDCR_CPU1_P0_EN_R")
		)
	)
	(footprint ""
		(layer "B.Cu")
		(at 361.317032 -261.747762 90)
		(property "Reference" "C2658"
			(at 0 0 90)
			(layer "B.SilkS")
			(hide yes)
			(effects
				(font
					(size 1.27 1.27)
				)
				(justify mirror)
			)
		)
		(property "Value" ""
			(at 0 0 90)
			(layer "B.Fab")
			(effects
				(font
					(size 1.27 1.27)
				)
				(justify mirror)
			)
		)
		(duplicate_pad_numbers_are_jumpers no)
		(fp_line
			(start 0.7874 -0.4064)
			(end -0.7874 -0.4064)
			(stroke
				(width 0.1524)
				(type default)
			)
			(layer "B.SilkS")
		)
		(fp_line
			(start -0.7874 -0.4064)
			(end -0.7874 0.4064)
			(stroke
				(width 0.1524)
				(type default)
			)
			(layer "B.SilkS")
		)
		(fp_line
			(start 0.7874 0.4064)
			(end 0.7874 -0.4064)
			(stroke
				(width 0.1524)
				(type default)
			)
			(layer "B.SilkS")
		)
		(fp_line
			(start -0.7874 0.4064)
			(end 0.7874 0.4064)
			(stroke
				(width 0.1524)
				(type default)
			)
			(layer "B.SilkS")
		)
		(fp_line
			(start 0.67945 -0.305054)
			(end 0.12065 -0.305054)
			(stroke
				(width 0.1)
				(type default)
			)
			(layer "B.Fab")
		)
		(fp_line
			(start 0.12065 -0.305054)
			(end 0.12065 -0.2794)
			(stroke
				(width 0.1)
				(type default)
			)
			(layer "B.Fab")
		)
		(fp_line
			(start -0.12065 -0.3048)
			(end -0.67945 -0.3048)
			(stroke
				(width 0.1)
				(type default)
			)
			(layer "B.Fab")
		)
		(fp_line
			(start -0.67945 -0.3048)
			(end -0.67945 0.3048)
			(stroke
				(width 0.1)
				(type default)
			)
			(layer "B.Fab")
		)
		(fp_line
			(start 0.12065 -0.2794)
			(end -0.12065 -0.2794)
			(stroke
				(width 0.1)
				(type default)
			)
			(layer "B.Fab")
		)
		(fp_line
			(start -0.12065 -0.2794)
			(end -0.12065 -0.3048)
			(stroke
				(width 0.1)
				(type default)
			)
			(layer "B.Fab")
		)
		(fp_line
			(start 0.12065 0.2794)
			(end 0.12065 0.3048)
			(stroke
				(width 0.1)
				(type default)
			)
			(layer "B.Fab")
		)
		(fp_line
			(start -0.120396 0.2794)
			(end 0.12065 0.2794)
			(stroke
				(width 0.1)
				(type default)
			)
			(layer "B.Fab")
		)
		(fp_line
			(start 0.67945 0.3048)
			(end 0.67945 -0.305054)
			(stroke
				(width 0.1)
				(type default)
			)
			(layer "B.Fab")
		)
		(fp_line
			(start 0.12065 0.3048)
			(end 0.67945 0.3048)
			(stroke
				(width 0.1)
				(type default)
			)
			(layer "B.Fab")
		)
		(fp_line
			(start -0.120396 0.3048)
			(end -0.120396 0.2794)
			(stroke
				(width 0.1)
				(type default)
			)
			(layer "B.Fab")
		)
		(fp_line
			(start -0.67945 0.3048)
			(end -0.120396 0.3048)
			(stroke
				(width 0.1)
				(type default)
			)
			(layer "B.Fab")
		)
		(pad "1" smd circle
			(at 0.40005 0 270)
			(size 0 0)
			(layers "B.Cu" "B.Mask" "B.Paste")
			(net "PVDD11_S3_P0")
		)
		(pad "2" smd circle
			(at -0.40005 0 270)
			(size 0 0)
			(layers "B.Cu" "B.Mask" "B.Paste")
			(net "GND")
		)
	)
	(footprint ""
		(layer "B.Cu")
		(at 53.518562 -388.011162 -90)
		(property "Reference" "C189"
			(at 0 0 90)
			(layer "B.SilkS")
			(hide yes)
			(effects
				(font
					(size 1.27 1.27)
				)
				(justify mirror)
			)
		)
		(property "Value" ""
			(at 0 0 90)
			(layer "B.Fab")
			(effects
				(font
					(size 1.27 1.27)
				)
				(justify mirror)
			)
		)
		(duplicate_pad_numbers_are_jumpers no)
		(fp_line
			(start -0.299974 0.150114)
			(end 0.299974 0.150114)
			(stroke
				(width 0.1)
				(type default)
			)
			(layer "B.Fab")
		)
		(fp_line
			(start 0.299974 0.150114)
			(end 0.299974 -0.150114)
			(stroke
				(width 0.1)
				(type default)
			)
			(layer "B.Fab")
		)
		(fp_line
			(start -0.299974 -0.150114)
			(end -0.299974 0.150114)
			(stroke
				(width 0.1)
				(type default)
			)
			(layer "B.Fab")
		)
		(fp_line
			(start 0.299974 -0.150114)
			(end -0.299974 -0.150114)
			(stroke
				(width 0.1)
				(type default)
			)
			(layer "B.Fab")
		)
		(pad "1" smd rect
			(at 0.2667 0 90)
			(size 0.3048 0.381)
			(layers "B.Cu" "B.Mask" "B.Paste")
			(net "P0V9_CPU1_RT_2D")
		)
		(pad "2" smd rect
			(at -0.2667 0 90)
			(size 0.3048 0.381)
			(layers "B.Cu" "B.Mask" "B.Paste")
			(net "GND")
		)
	)
)
